FILE_TYPE = CONNECTIVITY;
{Allegro Design Entry HDL 17.2-2016 S081 (4005846) 1/11/2022}
"PAGE_NUMBER" = 230;
0"NC";
1"P3V3_AUX\g";
2"P3V3_AUX\g";
3"P3V3_AUX\g";
4"P3V3_AUX\g";
5"P3V3_AUX\g";
6"P3V3_AUX\g";
7"P3V3_AUX\g";
8"P3V3_AUX\g";
9"GND\g";
10"GND\g";
11"GND\g";
12"GND\g";
13"GND\g";
14"GND\g";
15"GND\g";
16"GND\g";
17"GND\g";
18"GND\g";
19"GND\g";
20"HPDB_HSC_PWRGD";
21"PWRGD_P3V3_AUX_PDB";
22"HPDB_HSC_PWRGD_N";
23"HPDB_HSC_PWRGD_ISO";
24"PWRGD_P3V3_AUX_PDB_BUF";
25"FM_GPU_HSC_EN";
26"GPU_PRSNT";
27"FM_GPU_HSC_EN_BUF_R";
28"GPU_PRSNT_R";
29"PWRGD_P3V3_AUX_PDB_BUF_R";
30"PWRGD_P3V3_AUX_PDB_R";
31"FM_GPU_HSC_EN_BUF";
%"UNIVERSAL_POWER"
"1","(-1800,3350)","0","logical_power","I10";
;
HDL_POWER"P3V3_AUX"
CDS_LIB"logical_power";
"A"4;
%"UNIVERSAL_GND"
"1","(-150,1850)","0","logical_power","I12";
;
HDL_POWER"GND"
CDS_LIB"logical_power";
"A"13;
%"UNIVERSAL_GND"
"1","(925,2250)","0","logical_power","I13";
;
CDS_LIB"logical_power"
HDL_POWER"GND";
"A"10;
%"Q_CAP"
"1","(925,2475)","0","pure_quanta","I14";
;
PART_NUMBER"CH4104K1B00"
TOLERANCE"10%"
VOLTAGE"25V"
MATERIAL"X7R"
VALUE"0.1UF"
PACK_TYPE"0402"
$LOCATION"C1775"
CDS_LIB"pure_quanta"
CDS_LOCATION"C1775"
$SEC"1"
CDS_SEC"1";
"B"
$PN"2"10;
"A"
$PN"1"8;
%"UNIVERSAL_POWER"
"1","(925,2800)","0","logical_power","I15";
;
HDL_POWER"P3V3_AUX"
CDS_LIB"logical_power";
"A"8;
%"UNIVERSAL_GND"
"1","(1750,1550)","0","logical_power","I22";
;
CDS_LIB"logical_power"
HDL_POWER"GND";
"A"9;
%"Q_RES"
"1","(2000,2075)","0","pure_quanta","I24";
;
PART_NUMBER"CS03322FB03"
PACK_TYPE"0402LF"
MATERIAL"CHIP"
VALUE"33.2"
$LOCATION"R2944"
CDS_LIB"pure_quanta"
TOLERANCE"1%"
WATTAGE"1/16W"
CDS_LOCATION"R2944"
$SEC"1"
CDS_SEC"1";
"B"
$PN"2"31;
"A"
$PN"1"27;
%"Q_RES"
"2","(1725,2325)","0","pure_quanta","I25";
;
PART_NUMBER"CS24702JB10"
VALUE"4.7K"
TOLERANCE"5%"
WATTAGE"1/16W"
MATERIAL"EMPTY"
PACK_TYPE"0402LF"
$LOCATION"R2946"
CDS_LIB"pure_quanta"
CDS_LOCATION"R2946"
$SEC"1"
CDS_SEC"1";
"A"
$PN"1"5;
"B"
$PN"2"27;
%"UNIVERSAL_POWER"
"1","(1725,2575)","0","logical_power","I26";
;
HDL_POWER"P3V3_AUX"
CDS_LIB"logical_power";
"A"5;
%"Q_RES"
"2","(-1800,3100)","0","pure_quanta","I28";
;
PART_NUMBER"CS24702JB10"
VALUE"4.7K"
TOLERANCE"5%"
PACK_TYPE"0402LF"
MATERIAL"EMPTY"
WATTAGE"1/16W"
$LOCATION"R2940"
CDS_LIB"pure_quanta"
CDS_LOCATION"R2940"
$SEC"1"
CDS_SEC"1";
"A"
$PN"1"4;
"B"
$PN"2"25;
%"Q_RES"
"2","(-1775,2625)","0","pure_quanta","I29";
;
PART_NUMBER"CS41002FB09"
PACK_TYPE"0402LF"
TOLERANCE"1%"
WATTAGE"1/16W"
MATERIAL"CHIP"
VALUE"100K"
$LOCATION"R2941"
CDS_LIB"pure_quanta"
CDS_LOCATION"R2941"
$SEC"1"
CDS_SEC"1";
"A"
$PN"1"25;
"B"
$PN"2"14;
%"Q_RES"
"2","(1750,1775)","0","pure_quanta","I30";
;
PART_NUMBER"CS24702JB10"
WATTAGE"1/16W"
MATERIAL"EMPTY"
TOLERANCE"5%"
PACK_TYPE"0402LF"
VALUE"4.7K"
$LOCATION"R2948"
CDS_LIB"pure_quanta"
CDS_LOCATION"R2948"
$SEC"1"
CDS_SEC"1";
"A"
$PN"1"27;
"B"
$PN"2"9;
%"74LVC1G08W57"
"1","(250,2125)","0","pure_quanta","I31";
;
PART_NUMBER"AL1G0008020"
PART_TYPE"SMLF"
VALUE"74LVC1G08W5-7"
MATERIAL"IC"
$LOCATION"U278"
CDS_LIB"pure_quanta"
CDS_LMAN_SYM_OUTLINE"-150,150,150,-150"
NEEDS_NO_SIZE"TRUE"
CDS_LOCATION"U278"
$SEC"1"
CDS_SEC"1";
"VCC"
$PN"5"8;
"Y"
$PN"4"27;
"GND"
$PN"3"13;
"B"
$PN"2"28;
"A"
$PN"1"25;
%"Q_RES"
"1","(-1325,2125)","0","pure_quanta","I34";
;
PART_NUMBER"CS00002JB13"
WATTAGE"1/16W"
MATERIAL"CHIP"
TOLERANCE"5%"
VALUE"0"
PACK_TYPE"0402LF"
$LOCATION"R3770"
CDS_LIB"pure_quanta"
CDS_LOCATION"R3770"
$SEC"1"
CDS_SEC"1";
"B"
$PN"2"28;
"A"
$PN"1"26;
%"UNIVERSAL_GND"
"1","(-25,75)","0","logical_power","I36";
;
CDS_LIB"logical_power"
HDL_POWER"GND";
"A"15;
%"74LVC2G07DW7"
"1","(550,225)","0","pure_quanta","I37";
;
PART_NUMBER"AL002G07003"
MATERIAL"IC"
PART_TYPE"SMLF"
VALUE"74LVC2G07DW-7"
$LOCATION"U308"
CDS_LIB"pure_quanta"
NEEDS_NO_SIZE"TRUE"
CDS_LMAN_SYM_OUTLINE"-175,100,175,-100"
CDS_LOCATION"U308"
$SEC"1"
CDS_SEC"1";
"VCC"
$PN"5"6;
"GND"
$PN"2"15;
"2Y"
$PN"4"0;
"1Y"
$PN"6"29;
"2A"
$PN"3"0;
"1A"
$PN"1"30;
%"UNIVERSAL_POWER"
"1","(1250,-25)","0","logical_power","I38";
;
HDL_POWER"P3V3_AUX"
CDS_LIB"logical_power";
"A"6;
%"UNIVERSAL_GND"
"1","(1250,-575)","0","logical_power","I39";
;
CDS_LIB"logical_power"
HDL_POWER"GND";
"A"12;
%"Q_CAP"
"1","(1250,-350)","0","pure_quanta","I40";
;
PART_NUMBER"CH4104K1B00"
VALUE"0.1UF"
PACK_TYPE"0402"
VOLTAGE"25V"
TOLERANCE"10%"
MATERIAL"X7R"
$LOCATION"C2283"
CDS_LIB"pure_quanta"
CDS_LOCATION"C2283"
$SEC"1"
CDS_SEC"1";
"B"
$PN"2"12;
"A"
$PN"1"6;
%"Q_RES"
"1","(-1125,275)","0","pure_quanta","I41";
;
PART_NUMBER"CS00002JB13"
VALUE"0"
PACK_TYPE"0402LF"
WATTAGE"1/16W"
MATERIAL"CHIP"
TOLERANCE"5%"
$LOCATION"R4268"
CDS_LIB"pure_quanta"
CDS_LOCATION"R4268"
$SEC"1"
CDS_SEC"1";
"B"
$PN"2"30;
"A"
$PN"1"21;
%"Q_RES"
"2","(2175,-25)","0","pure_quanta","I43";
;
PART_NUMBER"CS24702JB10"
VALUE"4.7K"
TOLERANCE"5%"
MATERIAL"EMPTY"
WATTAGE"1/16W"
PACK_TYPE"0402LF"
$LOCATION"R4265"
CDS_LIB"pure_quanta"
CDS_LOCATION"R4265"
$SEC"1"
CDS_SEC"1";
"A"
$PN"1"29;
"B"
$PN"2"11;
%"UNIVERSAL_GND"
"1","(2175,-250)","0","logical_power","I44";
;
HDL_POWER"GND"
CDS_LIB"logical_power";
"A"11;
%"UNIVERSAL_POWER"
"1","(2150,775)","0","logical_power","I46";
;
HDL_POWER"P3V3_AUX"
CDS_LIB"logical_power";
"A"7;
%"Q_RES"
"2","(2150,525)","0","pure_quanta","I47";
;
PART_NUMBER"CS24702JB10"
VALUE"4.7K"
TOLERANCE"5%"
PACK_TYPE"0402LF"
WATTAGE"1/16W"
MATERIAL"CHIP"
$LOCATION"R4264"
CDS_LIB"pure_quanta"
CDS_LOCATION"R4264"
$SEC"1"
CDS_SEC"1";
"A"
$PN"1"7;
"B"
$PN"2"29;
%"Q_RES"
"1","(2400,275)","0","pure_quanta","I48";
;
PART_NUMBER"CS03322FB03"
MATERIAL"CHIP"
PACK_TYPE"0402LF"
VALUE"33.2"
$LOCATION"R4266"
CDS_LIB"pure_quanta"
TOLERANCE"1%"
WATTAGE"1/16W"
CDS_LOCATION"R4266"
$SEC"1"
CDS_SEC"1";
"B"
$PN"2"24;
"A"
$PN"1"29;
%"Q_RES"
"2","(-1100,-2275)","0","pure_quanta","I50";
;
PART_NUMBER"CS41002FB09"
MATERIAL"CHIP"
WATTAGE"1/16W"
TOLERANCE"1%"
VALUE"100K"
PACK_TYPE"0402LF"
$LOCATION"R4552"
CDS_LIB"pure_quanta"
CDS_LOCATION"R4552"
$SEC"1"
CDS_SEC"1";
"A"
$PN"1"20;
"B"
$PN"2"16;
%"Q_RES"
"2","(-1125,-1800)","0","pure_quanta","I51";
;
PART_NUMBER"CS35492FB03"
TOLERANCE"1%"
MATERIAL"EMPTY"
WATTAGE"1/16W"
VALUE"54.9K"
PACK_TYPE"0402LF"
$LOCATION"R4551"
CDS_LIB"pure_quanta"
CDS_LOCATION"R4551"
$SEC"1"
CDS_SEC"1";
"A"
$PN"1"1;
"B"
$PN"2"20;
%"UNIVERSAL_POWER"
"1","(-1125,-1550)","0","logical_power","I52";
;
HDL_POWER"P3V3_AUX"
CDS_LIB"logical_power";
"A"1;
%"MOSFET_NCH_DUAL"
"1","(0,-2025)","0","pure_quanta","I53";
;
PART_NUMBER"BAM138K0003"
PART_TYPE"SMLF"
VALUE"PJT138K"
MATERIAL"IC"
$LOCATION"Q145"
CDS_LIB"pure_quanta"
NEEDS_NO_SIZE"TRUE"
CDS_LMAN_SYM_OUTLINE"-150,150,150,-150"
CDS_LOCATION"Q145"
$SEC"1"
CDS_SEC"1";
"D1"
$PN"6"22;
"G1"
$PN"2"20;
"S1"
$PN"1"19;
%"UNIVERSAL_GND"
"1","(50,-2400)","0","logical_power","I54";
;
CDS_LIB"logical_power"
HDL_POWER"GND";
"A"19;
%"Q_RES"
"2","(50,-1425)","0","pure_quanta","I55";
;
PART_NUMBER"CS24702JB10"
PACK_TYPE"0402LF"
MATERIAL"CHIP"
WATTAGE"1/16W"
TOLERANCE"5%"
VALUE"4.7K"
$LOCATION"R4553"
CDS_LIB"pure_quanta"
CDS_LOCATION"R4553"
$SEC"1"
CDS_SEC"1";
"A"
$PN"1"2;
"B"
$PN"2"22;
%"UNIVERSAL_POWER"
"1","(50,-1200)","0","logical_power","I56";
;
HDL_POWER"P3V3_AUX"
CDS_LIB"logical_power";
"A"2;
%"UNIVERSAL_GND"
"1","(1200,-2100)","0","logical_power","I57";
;
CDS_LIB"logical_power"
HDL_POWER"GND";
"A"18;
%"MOSFET_NCH_DUAL"
"2","(1150,-1725)","0","pure_quanta","I58";
;
PART_NUMBER"BAM138K0003"
MATERIAL"IC"
VALUE"PJT138K"
PART_TYPE"SMLF"
$LOCATION"Q145"
CDS_LMAN_SYM_OUTLINE"-150,150,150,-150"
NEEDS_NO_SIZE"TRUE"
CDS_LIB"pure_quanta"
CDS_LOCATION"Q145"
$SEC"2"
CDS_SEC"2";
"S2"
$PN"4"18;
"G2"
$PN"5"22;
"D2"
$PN"3"23;
%"Q_RES"
"2","(1200,-1300)","0","pure_quanta","I59";
;
PART_NUMBER"CS24702JB10"
MATERIAL"CHIP"
TOLERANCE"5%"
WATTAGE"1/16W"
VALUE"4.7K"
PACK_TYPE"0402LF"
$LOCATION"R4554"
CDS_LIB"pure_quanta"
CDS_LOCATION"R4554"
$SEC"1"
CDS_SEC"1";
"A"
$PN"1"3;
"B"
$PN"2"23;
%"UNIVERSAL_GND"
"1","(-1775,2425)","0","logical_power","I6";
;
HDL_POWER"GND"
CDS_LIB"logical_power";
"A"14;
%"UNIVERSAL_POWER"
"1","(1200,-1075)","0","logical_power","I60";
;
HDL_POWER"P3V3_AUX"
CDS_LIB"logical_power";
"A"3;
%"UNIVERSAL_GND"
"1","(1975,-1975)","0","logical_power","I61";
;
CDS_LIB"logical_power"
HDL_POWER"GND";
"A"17;
%"Q_CAP"
"1","(1975,-1775)","0","pure_quanta","I62";
;
PART_NUMBER"TMP_QCH21006JB10"
VOLTAGE"50V"
PACK_TYPE"0402"
TOLERANCE"5%"
MATERIAL"EMPTY"
VALUE"1000PF"
$LOCATION"C2342"
CDS_LIB"pure_quanta"
CDS_LOCATION"C2342"
$SEC"1"
CDS_SEC"1";
"B"
$PN"2"17;
"A"
$PN"1"23;
%"UNIVERSAL_GND"
"1","(-1100,-2550)","0","logical_power","I64";
;
CDS_LIB"logical_power"
HDL_POWER"GND";
"A"16;
END.
